(kicad_pcb
	(version 20260206)
	(generator "pcbnew")
	(generator_version "10.0")
	(general
		(thickness 1.6)
		(legacy_teardrops no)
	)
	(paper "A4")
	(title_block
		(title "Bryce Canyon_SCC_16316-1_OCP.brd")
		(comment 1 "Bryce Canyon / footprint 482 of 1561 (U2), pads 478-602 of 896")
	)
	(layers
		(0 "F.Cu" signal "TOP")
		(4 "In1.Cu" signal "L2GND")
		(6 "In2.Cu" signal "L3")
		(8 "In3.Cu" signal "L4VCC")
		(10 "In4.Cu" signal "L5VCC")
		(12 "In5.Cu" signal "L6")
		(14 "In6.Cu" signal "L7GND")
		(2 "B.Cu" signal "BOTTOM")
		(9 "F.Adhes" user "F.Adhesive")
		(11 "B.Adhes" user "B.Adhesive")
		(13 "F.Paste" user "Package Geometry/Pastemask Top")
		(15 "B.Paste" user "Package Geometry/Pastemask Bottom")
		(5 "F.SilkS" user "Ref Des/Silkscreen Top")
		(7 "B.SilkS" user "Ref Des/Silkscreen Bottom")
		(1 "F.Mask" user "Board Geometry/Soldermask Top")
		(3 "B.Mask" user "Board Geometry/Soldermask Bottom")
		(17 "Dwgs.User" user "User.Drawings")
		(19 "Cmts.User" user "User.Comments")
		(21 "Eco1.User" user "User.Eco1")
		(23 "Eco2.User" user "User.Eco2")
		(25 "Edge.Cuts" user "Board Geometry/Outline")
		(27 "Margin" user)
		(31 "F.CrtYd" user "Package Geometry/Place Bound Top")
		(29 "B.CrtYd" user "Package Geometry/Place Bound Bottom")
		(35 "F.Fab" user "Ref Des/Assembly Top")
		(33 "B.Fab" user "Ref Des/Assembly Bottom")
	)
	(footprint ""
		(layer "F.Cu")
		(at 174.999904 -39.99992)
		(property "Reference" "U2"
			(at 0 0 0)
			(layer "F.SilkS")
			(hide yes)
			(effects
				(font
					(size 1.27 1.27)
				)
			)
		)
		(property "Value" "SAS3008C0-1-DB-500020657-1-GP"
			(at -20.374102 -5.0292 0)
			(unlocked yes)
			(layer "F.Fab")
			(hide yes)
			(effects
				(font
					(size 1.016 1.016)
					(thickness 0.1524)
				)
			)
		)
		(property "Device Type" "BGA896D25H78"
			(at -20.374102 -6.5532 0)
			(unlocked yes)
			(layer "F.Fab")
			(hide yes)
			(effects
				(font
					(size 1.016 1.016)
					(thickness 0.1524)
				)
			)
		)
		(duplicate_pad_numbers_are_jumpers no)
		(pad "G2" smd circle
			(at -10.80008 -6.800088)
			(size 0.3556 0.3556)
			(layers "F.Cu" "F.Mask" "F.Paste")
			(net "Net_1181")
		)
		(pad "G3" smd circle
			(at -9.99998 -6.800088)
			(size 0.3556 0.3556)
			(layers "F.Cu" "F.Mask" "F.Paste")
			(net "Net_1182")
		)
		(pad "G4" smd circle
			(at -9.19988 -6.800088)
			(size 0.3556 0.3556)
			(layers "F.Cu" "F.Mask" "F.Paste")
			(net "GND")
		)
		(pad "G5" smd circle
			(at -8.400034 -6.800088)
			(size 0.3556 0.3556)
			(layers "F.Cu" "F.Mask" "F.Paste")
			(net "P1V8_C")
		)
		(pad "G6" smd circle
			(at -7.599934 -6.800088)
			(size 0.3556 0.3556)
			(layers "F.Cu" "F.Mask" "F.Paste")
			(net "Net_1183")
		)
		(pad "G7" smd circle
			(at -6.800088 -6.800088)
			(size 0.3556 0.3556)
			(layers "F.Cu" "F.Mask" "F.Paste")
			(net "GND")
		)
		(pad "G8" smd circle
			(at -5.999988 -6.800088)
			(size 0.3556 0.3556)
			(layers "F.Cu" "F.Mask" "F.Paste")
			(net "GND")
		)
		(pad "G9" smd circle
			(at -5.199888 -6.800088)
			(size 0.3556 0.3556)
			(layers "F.Cu" "F.Mask" "F.Paste")
			(net "GND")
		)
		(pad "G10" smd circle
			(at -4.400042 -6.800088)
			(size 0.3556 0.3556)
			(layers "F.Cu" "F.Mask" "F.Paste")
			(net "GND")
		)
		(pad "G11" smd circle
			(at -3.599942 -6.800088)
			(size 0.3556 0.3556)
			(layers "F.Cu" "F.Mask" "F.Paste")
			(net "GND")
		)
		(pad "G12" smd circle
			(at -2.800096 -6.800088)
			(size 0.3556 0.3556)
			(layers "F.Cu" "F.Mask" "F.Paste")
			(net "GND")
		)
		(pad "G13" smd circle
			(at -1.999996 -6.800088)
			(size 0.3556 0.3556)
			(layers "F.Cu" "F.Mask" "F.Paste")
			(net "GND")
		)
		(pad "G14" smd circle
			(at -1.199896 -6.800088)
			(size 0.3556 0.3556)
			(layers "F.Cu" "F.Mask" "F.Paste")
			(net "GND")
		)
		(pad "G15" smd circle
			(at -0.40005 -6.800088)
			(size 0.3556 0.3556)
			(layers "F.Cu" "F.Mask" "F.Paste")
			(net "GND")
		)
		(pad "G16" smd circle
			(at 0.40005 -6.800088)
			(size 0.3556 0.3556)
			(layers "F.Cu" "F.Mask" "F.Paste")
			(net "GND")
		)
		(pad "G17" smd circle
			(at 1.199896 -6.800088)
			(size 0.3556 0.3556)
			(layers "F.Cu" "F.Mask" "F.Paste")
			(net "GND")
		)
		(pad "G18" smd circle
			(at 1.999996 -6.800088)
			(size 0.3556 0.3556)
			(layers "F.Cu" "F.Mask" "F.Paste")
			(net "GND")
		)
		(pad "G19" smd circle
			(at 2.800096 -6.800088)
			(size 0.3556 0.3556)
			(layers "F.Cu" "F.Mask" "F.Paste")
			(net "GND")
		)
		(pad "G20" smd circle
			(at 3.599942 -6.800088)
			(size 0.3556 0.3556)
			(layers "F.Cu" "F.Mask" "F.Paste")
			(net "GND")
		)
		(pad "G21" smd circle
			(at 4.400042 -6.800088)
			(size 0.3556 0.3556)
			(layers "F.Cu" "F.Mask" "F.Paste")
			(net "GND")
		)
		(pad "G22" smd circle
			(at 5.199888 -6.800088)
			(size 0.3556 0.3556)
			(layers "F.Cu" "F.Mask" "F.Paste")
			(net "GND")
		)
		(pad "G23" smd circle
			(at 5.999988 -6.800088)
			(size 0.3556 0.3556)
			(layers "F.Cu" "F.Mask" "F.Paste")
			(net "GND")
		)
		(pad "G24" smd circle
			(at 6.800088 -6.800088)
			(size 0.3556 0.3556)
			(layers "F.Cu" "F.Mask" "F.Paste")
			(net "GND")
		)
		(pad "G25" smd circle
			(at 7.599934 -6.800088)
			(size 0.3556 0.3556)
			(layers "F.Cu" "F.Mask" "F.Paste")
			(net "GND")
		)
		(pad "G26" smd circle
			(at 8.400034 -6.800088)
			(size 0.3556 0.3556)
			(layers "F.Cu" "F.Mask" "F.Paste")
			(net "GND")
		)
		(pad "G27" smd circle
			(at 9.19988 -6.800088)
			(size 0.3556 0.3556)
			(layers "F.Cu" "F.Mask" "F.Paste")
			(net "P1V8_C")
		)
		(pad "G28" smd circle
			(at 9.99998 -6.800088)
			(size 0.3556 0.3556)
			(layers "F.Cu" "F.Mask" "F.Paste")
			(net "XM_ADDR_15")
		)
		(pad "G29" smd circle
			(at 10.80008 -6.800088)
			(size 0.3556 0.3556)
			(layers "F.Cu" "F.Mask" "F.Paste")
			(net "XM_ADDR_21")
		)
		(pad "G30" smd circle
			(at 11.599926 -6.800088)
			(size 0.3556 0.3556)
			(layers "F.Cu" "F.Mask" "F.Paste")
			(net "XM_DATA_13")
		)
		(pad "H1" smd circle
			(at -11.599926 -5.999988)
			(size 0.3556 0.3556)
			(layers "F.Cu" "F.Mask" "F.Paste")
			(net "GND")
		)
		(pad "H2" smd circle
			(at -10.80008 -5.999988)
			(size 0.3556 0.3556)
			(layers "F.Cu" "F.Mask" "F.Paste")
			(net "Net_1184")
		)
		(pad "H3" smd circle
			(at -9.99998 -5.999988)
			(size 0.3556 0.3556)
			(layers "F.Cu" "F.Mask" "F.Paste")
			(net "Net_1185")
		)
		(pad "H4" smd circle
			(at -9.19988 -5.999988)
			(size 0.3556 0.3556)
			(layers "F.Cu" "F.Mask" "F.Paste")
			(net "P1V8_C")
		)
		(pad "H5" smd circle
			(at -8.400034 -5.999988)
			(size 0.3556 0.3556)
			(layers "F.Cu" "F.Mask" "F.Paste")
			(net "GND")
		)
		(pad "H6" smd circle
			(at -7.599934 -5.999988)
			(size 0.3556 0.3556)
			(layers "F.Cu" "F.Mask" "F.Paste")
			(net "Net_1186")
		)
		(pad "H7" smd circle
			(at -6.800088 -5.999988)
			(size 0.3556 0.3556)
			(layers "F.Cu" "F.Mask" "F.Paste")
			(net "GND")
		)
		(pad "H8" smd circle
			(at -5.999988 -5.999988)
			(size 0.3556 0.3556)
			(layers "F.Cu" "F.Mask" "F.Paste")
			(net "GND")
		)
		(pad "H9" smd circle
			(at -5.199888 -5.999988)
			(size 0.3556 0.3556)
			(layers "F.Cu" "F.Mask" "F.Paste")
			(net "GND")
		)
		(pad "H10" smd circle
			(at -4.400042 -5.999988)
			(size 0.3556 0.3556)
			(layers "F.Cu" "F.Mask" "F.Paste")
			(net "GND")
		)
		(pad "H11" smd circle
			(at -3.599942 -5.999988)
			(size 0.3556 0.3556)
			(layers "F.Cu" "F.Mask" "F.Paste")
			(net "GND")
		)
		(pad "H12" smd circle
			(at -2.800096 -5.999988)
			(size 0.3556 0.3556)
			(layers "F.Cu" "F.Mask" "F.Paste")
			(net "GND")
		)
		(pad "H13" smd circle
			(at -1.999996 -5.999988)
			(size 0.3556 0.3556)
			(layers "F.Cu" "F.Mask" "F.Paste")
			(net "GND")
		)
		(pad "H14" smd circle
			(at -1.199896 -5.999988)
			(size 0.3556 0.3556)
			(layers "F.Cu" "F.Mask" "F.Paste")
			(net "GND")
		)
		(pad "H15" smd circle
			(at -0.40005 -5.999988)
			(size 0.3556 0.3556)
			(layers "F.Cu" "F.Mask" "F.Paste")
			(net "GND")
		)
		(pad "H16" smd circle
			(at 0.40005 -5.999988)
			(size 0.3556 0.3556)
			(layers "F.Cu" "F.Mask" "F.Paste")
			(net "GND")
		)
		(pad "H17" smd circle
			(at 1.199896 -5.999988)
			(size 0.3556 0.3556)
			(layers "F.Cu" "F.Mask" "F.Paste")
			(net "GND")
		)
		(pad "H18" smd circle
			(at 1.999996 -5.999988)
			(size 0.3556 0.3556)
			(layers "F.Cu" "F.Mask" "F.Paste")
			(net "GND")
		)
		(pad "H19" smd circle
			(at 2.800096 -5.999988)
			(size 0.3556 0.3556)
			(layers "F.Cu" "F.Mask" "F.Paste")
			(net "GND")
		)
		(pad "H20" smd circle
			(at 3.599942 -5.999988)
			(size 0.3556 0.3556)
			(layers "F.Cu" "F.Mask" "F.Paste")
			(net "GND")
		)
		(pad "H21" smd circle
			(at 4.400042 -5.999988)
			(size 0.3556 0.3556)
			(layers "F.Cu" "F.Mask" "F.Paste")
			(net "GND")
		)
		(pad "H22" smd circle
			(at 5.199888 -5.999988)
			(size 0.3556 0.3556)
			(layers "F.Cu" "F.Mask" "F.Paste")
			(net "GND")
		)
		(pad "H23" smd circle
			(at 5.999988 -5.999988)
			(size 0.3556 0.3556)
			(layers "F.Cu" "F.Mask" "F.Paste")
			(net "GND")
		)
		(pad "H24" smd circle
			(at 6.800088 -5.999988)
			(size 0.3556 0.3556)
			(layers "F.Cu" "F.Mask" "F.Paste")
			(net "GND")
		)
		(pad "H25" smd circle
			(at 7.599934 -5.999988)
			(size 0.3556 0.3556)
			(layers "F.Cu" "F.Mask" "F.Paste")
			(net "GND")
		)
		(pad "H26" smd circle
			(at 8.400034 -5.999988)
			(size 0.3556 0.3556)
			(layers "F.Cu" "F.Mask" "F.Paste")
			(net "P1V8_C")
		)
		(pad "H27" smd circle
			(at 9.19988 -5.999988)
			(size 0.3556 0.3556)
			(layers "F.Cu" "F.Mask" "F.Paste")
			(net "GND")
		)
		(pad "H28" smd circle
			(at 9.99998 -5.999988)
			(size 0.3556 0.3556)
			(layers "F.Cu" "F.Mask" "F.Paste")
			(net "XM_DATA_0")
		)
		(pad "H29" smd circle
			(at 10.80008 -5.999988)
			(size 0.3556 0.3556)
			(layers "F.Cu" "F.Mask" "F.Paste")
			(net "XM_ADDR_25")
		)
		(pad "H30" smd circle
			(at 11.599926 -5.999988)
			(size 0.3556 0.3556)
			(layers "F.Cu" "F.Mask" "F.Paste")
			(net "XM_ADDR_18")
		)
		(pad "J1" smd circle
			(at -11.599926 -5.199888)
			(size 0.3556 0.3556)
			(layers "F.Cu" "F.Mask" "F.Paste")
			(net "Net_1201")
		)
		(pad "J2" smd circle
			(at -10.80008 -5.199888)
			(size 0.3556 0.3556)
			(layers "F.Cu" "F.Mask" "F.Paste")
			(net "Net_1187")
		)
		(pad "J3" smd circle
			(at -9.99998 -5.199888)
			(size 0.3556 0.3556)
			(layers "F.Cu" "F.Mask" "F.Paste")
			(net "Net_1188")
		)
		(pad "J4" smd circle
			(at -9.19988 -5.199888)
			(size 0.3556 0.3556)
			(layers "F.Cu" "F.Mask" "F.Paste")
			(net "GND")
		)
		(pad "J5" smd circle
			(at -8.400034 -5.199888)
			(size 0.3556 0.3556)
			(layers "F.Cu" "F.Mask" "F.Paste")
			(net "P1V8_C")
		)
		(pad "J6" smd circle
			(at -7.599934 -5.199888)
			(size 0.3556 0.3556)
			(layers "F.Cu" "F.Mask" "F.Paste")
			(net "Net_1189")
		)
		(pad "J7" smd circle
			(at -6.800088 -5.199888)
			(size 0.3556 0.3556)
			(layers "F.Cu" "F.Mask" "F.Paste")
			(net "GND")
		)
		(pad "J8" smd circle
			(at -5.999988 -5.199888)
			(size 0.3556 0.3556)
			(layers "F.Cu" "F.Mask" "F.Paste")
			(net "GND")
		)
		(pad "J9" smd circle
			(at -5.199888 -5.199888)
			(size 0.3556 0.3556)
			(layers "F.Cu" "F.Mask" "F.Paste")
			(net "GND")
		)
		(pad "J10" smd circle
			(at -4.400042 -5.199888)
			(size 0.3556 0.3556)
			(layers "F.Cu" "F.Mask" "F.Paste")
			(net "GND")
		)
		(pad "J11" smd circle
			(at -3.599942 -5.199888)
			(size 0.3556 0.3556)
			(layers "F.Cu" "F.Mask" "F.Paste")
			(net "GND")
		)
		(pad "J12" smd circle
			(at -2.800096 -5.199888)
			(size 0.3556 0.3556)
			(layers "F.Cu" "F.Mask" "F.Paste")
			(net "P0V975")
		)
		(pad "J13" smd circle
			(at -1.999996 -5.199888)
			(size 0.3556 0.3556)
			(layers "F.Cu" "F.Mask" "F.Paste")
			(net "GND")
		)
		(pad "J14" smd circle
			(at -1.199896 -5.199888)
			(size 0.3556 0.3556)
			(layers "F.Cu" "F.Mask" "F.Paste")
			(net "GND")
		)
		(pad "J15" smd circle
			(at -0.40005 -5.199888)
			(size 0.3556 0.3556)
			(layers "F.Cu" "F.Mask" "F.Paste")
			(net "GND")
		)
		(pad "J16" smd circle
			(at 0.40005 -5.199888)
			(size 0.3556 0.3556)
			(layers "F.Cu" "F.Mask" "F.Paste")
			(net "GND")
		)
		(pad "J17" smd circle
			(at 1.199896 -5.199888)
			(size 0.3556 0.3556)
			(layers "F.Cu" "F.Mask" "F.Paste")
			(net "GND")
		)
		(pad "J18" smd circle
			(at 1.999996 -5.199888)
			(size 0.3556 0.3556)
			(layers "F.Cu" "F.Mask" "F.Paste")
			(net "GND")
		)
		(pad "J19" smd circle
			(at 2.800096 -5.199888)
			(size 0.3556 0.3556)
			(layers "F.Cu" "F.Mask" "F.Paste")
			(net "GND")
		)
		(pad "J20" smd circle
			(at 3.599942 -5.199888)
			(size 0.3556 0.3556)
			(layers "F.Cu" "F.Mask" "F.Paste")
			(net "GND")
		)
		(pad "J21" smd circle
			(at 4.400042 -5.199888)
			(size 0.3556 0.3556)
			(layers "F.Cu" "F.Mask" "F.Paste")
			(net "GND")
		)
		(pad "J22" smd circle
			(at 5.199888 -5.199888)
			(size 0.3556 0.3556)
			(layers "F.Cu" "F.Mask" "F.Paste")
			(net "GND")
		)
		(pad "J23" smd circle
			(at 5.999988 -5.199888)
			(size 0.3556 0.3556)
			(layers "F.Cu" "F.Mask" "F.Paste")
			(net "GND")
		)
		(pad "J24" smd circle
			(at 6.800088 -5.199888)
			(size 0.3556 0.3556)
			(layers "F.Cu" "F.Mask" "F.Paste")
			(net "GND")
		)
		(pad "J25" smd circle
			(at 7.599934 -5.199888)
			(size 0.3556 0.3556)
			(layers "F.Cu" "F.Mask" "F.Paste")
			(net "GND")
		)
		(pad "J26" smd circle
			(at 8.400034 -5.199888)
			(size 0.3556 0.3556)
			(layers "F.Cu" "F.Mask" "F.Paste")
			(net "GND")
		)
		(pad "J27" smd circle
			(at 9.19988 -5.199888)
			(size 0.3556 0.3556)
			(layers "F.Cu" "F.Mask" "F.Paste")
			(net "P1V8_C")
		)
		(pad "J28" smd circle
			(at 9.99998 -5.199888)
			(size 0.3556 0.3556)
			(layers "F.Cu" "F.Mask" "F.Paste")
			(net "XM_DATA_12")
		)
		(pad "J29" smd circle
			(at 10.80008 -5.199888)
			(size 0.3556 0.3556)
			(layers "F.Cu" "F.Mask" "F.Paste")
			(net "XM_ADDR_22")
		)
		(pad "J30" smd circle
			(at 11.599926 -5.199888)
			(size 0.3556 0.3556)
			(layers "F.Cu" "F.Mask" "F.Paste")
			(net "XM_ADDR_24")
		)
		(pad "K1" smd circle
			(at -11.599926 -4.400042)
			(size 0.3556 0.3556)
			(layers "F.Cu" "F.Mask" "F.Paste")
			(net "SIO_LOAD_1")
		)
		(pad "K2" smd circle
			(at -10.80008 -4.400042)
			(size 0.3556 0.3556)
			(layers "F.Cu" "F.Mask" "F.Paste")
			(net "SIO_DOUT_0")
		)
		(pad "K3" smd circle
			(at -9.99998 -4.400042)
			(size 0.3556 0.3556)
			(layers "F.Cu" "F.Mask" "F.Paste")
			(net "GND")
		)
		(pad "K4" smd circle
			(at -9.19988 -4.400042)
			(size 0.3556 0.3556)
			(layers "F.Cu" "F.Mask" "F.Paste")
			(net "P1V8_C")
		)
		(pad "K5" smd circle
			(at -8.400034 -4.400042)
			(size 0.3556 0.3556)
			(layers "F.Cu" "F.Mask" "F.Paste")
			(net "GND")
		)
		(pad "K6" smd circle
			(at -7.599934 -4.400042)
			(size 0.3556 0.3556)
			(layers "F.Cu" "F.Mask" "F.Paste")
			(net "Net_1190")
		)
		(pad "K7" smd circle
			(at -6.800088 -4.400042)
			(size 0.3556 0.3556)
			(layers "F.Cu" "F.Mask" "F.Paste")
			(net "GND")
		)
		(pad "K8" smd circle
			(at -5.999988 -4.400042)
			(size 0.3556 0.3556)
			(layers "F.Cu" "F.Mask" "F.Paste")
			(net "GND")
		)
		(pad "K9" smd circle
			(at -5.199888 -4.400042)
			(size 0.3556 0.3556)
			(layers "F.Cu" "F.Mask" "F.Paste")
			(net "GND")
		)
		(pad "K10" smd circle
			(at -4.400042 -4.400042)
			(size 0.3556 0.3556)
			(layers "F.Cu" "F.Mask" "F.Paste")
			(net "GND")
		)
		(pad "K11" smd circle
			(at -3.599942 -4.400042)
			(size 0.3556 0.3556)
			(layers "F.Cu" "F.Mask" "F.Paste")
			(net "GND")
		)
		(pad "K12" smd circle
			(at -2.800096 -4.400042)
			(size 0.3556 0.3556)
			(layers "F.Cu" "F.Mask" "F.Paste")
			(net "GND")
		)
		(pad "K13" smd circle
			(at -1.999996 -4.400042)
			(size 0.3556 0.3556)
			(layers "F.Cu" "F.Mask" "F.Paste")
			(net "P0V975")
		)
		(pad "K14" smd circle
			(at -1.199896 -4.400042)
			(size 0.3556 0.3556)
			(layers "F.Cu" "F.Mask" "F.Paste")
			(net "GND")
		)
		(pad "K15" smd circle
			(at -0.40005 -4.400042)
			(size 0.3556 0.3556)
			(layers "F.Cu" "F.Mask" "F.Paste")
			(net "GND")
		)
		(pad "K16" smd circle
			(at 0.40005 -4.400042)
			(size 0.3556 0.3556)
			(layers "F.Cu" "F.Mask" "F.Paste")
			(net "GND")
		)
		(pad "K17" smd circle
			(at 1.199896 -4.400042)
			(size 0.3556 0.3556)
			(layers "F.Cu" "F.Mask" "F.Paste")
			(net "GND")
		)
		(pad "K18" smd circle
			(at 1.999996 -4.400042)
			(size 0.3556 0.3556)
			(layers "F.Cu" "F.Mask" "F.Paste")
			(net "GND")
		)
		(pad "K19" smd circle
			(at 2.800096 -4.400042)
			(size 0.3556 0.3556)
			(layers "F.Cu" "F.Mask" "F.Paste")
			(net "GND")
		)
		(pad "K20" smd circle
			(at 3.599942 -4.400042)
			(size 0.3556 0.3556)
			(layers "F.Cu" "F.Mask" "F.Paste")
			(net "GND")
		)
		(pad "K21" smd circle
			(at 4.400042 -4.400042)
			(size 0.3556 0.3556)
			(layers "F.Cu" "F.Mask" "F.Paste")
			(net "P0V975")
		)
		(pad "K22" smd circle
			(at 5.199888 -4.400042)
			(size 0.3556 0.3556)
			(layers "F.Cu" "F.Mask" "F.Paste")
			(net "GND")
		)
		(pad "K23" smd circle
			(at 5.999988 -4.400042)
			(size 0.3556 0.3556)
			(layers "F.Cu" "F.Mask" "F.Paste")
			(net "GND")
		)
		(pad "K24" smd circle
			(at 6.800088 -4.400042)
			(size 0.3556 0.3556)
			(layers "F.Cu" "F.Mask" "F.Paste")
			(net "GND")
		)
		(pad "K25" smd circle
			(at 7.599934 -4.400042)
			(size 0.3556 0.3556)
			(layers "F.Cu" "F.Mask" "F.Paste")
			(net "GND")
		)
		(pad "K26" smd circle
			(at 8.400034 -4.400042)
			(size 0.3556 0.3556)
			(layers "F.Cu" "F.Mask" "F.Paste")
			(net "P1V8_C")
		)
		(pad "K27" smd circle
			(at 9.19988 -4.400042)
			(size 0.3556 0.3556)
			(layers "F.Cu" "F.Mask" "F.Paste")
			(net "GND")
		)
		(pad "K28" smd circle
			(at 9.99998 -4.400042)
			(size 0.3556 0.3556)
			(layers "F.Cu" "F.Mask" "F.Paste")
			(net "XM_DATA_2")
		)
		(pad "K29" smd circle
			(at 10.80008 -4.400042)
			(size 0.3556 0.3556)
			(layers "F.Cu" "F.Mask" "F.Paste")
			(net "XM_ADDR_23")
		)
		(pad "K30" smd circle
			(at 11.599926 -4.400042)
			(size 0.3556 0.3556)
			(layers "F.Cu" "F.Mask" "F.Paste")
			(net "XM_DATA_1")
		)
		(pad "L1" smd circle
			(at -11.599926 -3.599942)
			(size 0.3556 0.3556)
			(layers "F.Cu" "F.Mask" "F.Paste")
			(net "SIO_CLK_1")
		)
		(pad "L2" smd circle
			(at -10.80008 -3.599942)
			(size 0.3556 0.3556)
			(layers "F.Cu" "F.Mask" "F.Paste")
			(net "SIO_DIN_1")
		)
		(pad "L3" smd circle
			(at -9.99998 -3.599942)
			(size 0.3556 0.3556)
			(layers "F.Cu" "F.Mask" "F.Paste")
			(net "Net_1191")
		)
		(pad "L4" smd circle
			(at -9.19988 -3.599942)
			(size 0.3556 0.3556)
			(layers "F.Cu" "F.Mask" "F.Paste")
			(net "GND")
		)
		(pad "L5" smd circle
			(at -8.400034 -3.599942)
			(size 0.3556 0.3556)
			(layers "F.Cu" "F.Mask" "F.Paste")
			(net "P1V8_C")
		)
		(pad "L6" smd circle
			(at -7.599934 -3.599942)
			(size 0.3556 0.3556)
			(layers "F.Cu" "F.Mask" "F.Paste")
			(net "ICE1_TDI")
		)
	)
)
